(kicad_pcb
	(version 20260206)
	(generator "pcbnew")
	(generator_version "10.0")
	(general
		(thickness 1.6)
		(legacy_teardrops no)
	)
	(paper "A4")
	(title_block
		(title "Wiwynn_Tioga_Pass_MB.brd")
		(comment 1 "Tioga Pass / footprint 437 of 4770 (J1G3), pads 1-123 of 291")
	)
	(layers
		(0 "F.Cu" signal "TOP")
		(4 "In1.Cu" signal "L2GND")
		(6 "In2.Cu" signal "L3")
		(8 "In3.Cu" signal "L4GND")
		(10 "In4.Cu" signal "L5")
		(12 "In5.Cu" signal "L6GND")
		(14 "In6.Cu" signal "L7VCC")
		(16 "In7.Cu" signal "L8VCC")
		(18 "In8.Cu" signal "L9GND")
		(20 "In9.Cu" signal "L10")
		(22 "In10.Cu" signal "L11GND")
		(24 "In11.Cu" signal "L12")
		(26 "In12.Cu" signal "L13GND")
		(2 "B.Cu" signal "BOTTOM")
		(9 "F.Adhes" user "F.Adhesive")
		(11 "B.Adhes" user "B.Adhesive")
		(13 "F.Paste" user "Package Geometry/Pastemask Top")
		(15 "B.Paste" user "Package Geometry/Pastemask Bottom")
		(5 "F.SilkS" user "Ref Des/Silkscreen Top")
		(7 "B.SilkS" user "Ref Des/Silkscreen Bottom")
		(1 "F.Mask" user "Board Geometry/Soldermask Top")
		(3 "B.Mask" user "Board Geometry/Soldermask Bottom")
		(17 "Dwgs.User" user "User.Drawings")
		(19 "Cmts.User" user "User.Comments")
		(21 "Eco1.User" user "User.Eco1")
		(23 "Eco2.User" user "User.Eco2")
		(25 "Edge.Cuts" user "Board Geometry/Outline")
		(27 "Margin" user)
		(31 "F.CrtYd" user "Package Geometry/Place Bound Top")
		(29 "B.CrtYd" user "Package Geometry/Place Bound Bottom")
		(35 "F.Fab" user "Ref Des/Assembly Top")
		(33 "B.Fab" user "Ref Des/Assembly Bottom")
	)
	(footprint ""
		(layer "F.Cu")
		(at 29.699458 3.778758 90)
		(property "Reference" "J1G3"
			(at 7.054088 34.562542 0)
			(unlocked yes)
			(layer "F.SilkS")
			(effects
				(font
					(size 0.7874 0.5842)
					(thickness 0.1524)
				)
				(justify left)
			)
		)
		(property "Value" ""
			(at 0 0 90)
			(layer "F.Fab")
			(effects
				(font
					(size 1.27 1.27)
				)
			)
		)
		(duplicate_pad_numbers_are_jumpers no)
		(pad "" thru_hole circle
			(at 2.29997 -5.649976 90)
			(size 2.8194 2.8194)
			(drill 2.4384)
			(layers "*.Cu" "*.Mask")
			(remove_unused_layers no)
			(clearance 0.127)
			(thermal_gap 0.127)
		)
		(pad "" thru_hole oval
			(at 2.29997 68.90004 90)
			(size 2.8194 1.5748)
			(drill oval 2.4384 1.1938)
			(layers "*.Cu" "*.Mask")
			(remove_unused_layers no)
			(clearance 0.127)
			(thermal_gap 0.127)
		)
		(pad "" thru_hole circle
			(at 2.29997 132.299964 90)
			(size 2.8194 2.8194)
			(drill 2.4384)
			(layers "*.Cu" "*.Mask")
			(remove_unused_layers no)
			(clearance 0.127)
			(thermal_gap 0.127)
		)
		(pad "1" smd rect
			(at 0 0 90)
			(size 1.8034 0.508)
			(layers "F.Cu" "F.Mask" "F.Paste")
			(net "P12V_NVDIMM_GHJ")
		)
		(pad "2" smd rect
			(at 0 0.849884 90)
			(size 1.8034 0.508)
			(layers "F.Cu" "F.Mask" "F.Paste")
			(net "GND")
		)
		(pad "3" smd rect
			(at 0 1.700022 90)
			(size 1.8034 0.508)
			(layers "F.Cu" "F.Mask" "F.Paste")
			(net "M_J_DQ<5>")
		)
		(pad "4" smd rect
			(at 0 2.549906 90)
			(size 1.8034 0.508)
			(layers "F.Cu" "F.Mask" "F.Paste")
			(net "GND")
		)
		(pad "5" smd rect
			(at 0 3.400044 90)
			(size 1.8034 0.508)
			(layers "F.Cu" "F.Mask" "F.Paste")
			(net "M_J_DQ<1>")
		)
		(pad "6" smd rect
			(at 0 4.249928 90)
			(size 1.8034 0.508)
			(layers "F.Cu" "F.Mask" "F.Paste")
			(net "GND")
		)
		(pad "7" smd rect
			(at 0 5.100066 90)
			(size 1.8034 0.508)
			(layers "F.Cu" "F.Mask" "F.Paste")
			(net "M_J_DQS_DP<9>")
		)
		(pad "8" smd rect
			(at 0 5.94995 90)
			(size 1.8034 0.508)
			(layers "F.Cu" "F.Mask" "F.Paste")
			(net "M_J_DQS_DN<9>")
		)
		(pad "9" smd rect
			(at 0 6.800088 90)
			(size 1.8034 0.508)
			(layers "F.Cu" "F.Mask" "F.Paste")
			(net "GND")
		)
		(pad "10" smd rect
			(at 0 7.649972 90)
			(size 1.8034 0.508)
			(layers "F.Cu" "F.Mask" "F.Paste")
			(net "M_J_DQ<7>")
		)
		(pad "11" smd rect
			(at 0 8.50011 90)
			(size 1.8034 0.508)
			(layers "F.Cu" "F.Mask" "F.Paste")
			(net "GND")
		)
		(pad "12" smd rect
			(at 0 9.349994 90)
			(size 1.8034 0.508)
			(layers "F.Cu" "F.Mask" "F.Paste")
			(net "M_J_DQ<3>")
		)
		(pad "13" smd rect
			(at 0 10.199878 90)
			(size 1.8034 0.508)
			(layers "F.Cu" "F.Mask" "F.Paste")
			(net "GND")
		)
		(pad "14" smd rect
			(at 0 11.050016 90)
			(size 1.8034 0.508)
			(layers "F.Cu" "F.Mask" "F.Paste")
			(net "M_J_DQ<13>")
		)
		(pad "15" smd rect
			(at 0 11.8999 90)
			(size 1.8034 0.508)
			(layers "F.Cu" "F.Mask" "F.Paste")
			(net "GND")
		)
		(pad "16" smd rect
			(at 0 12.750038 90)
			(size 1.8034 0.508)
			(layers "F.Cu" "F.Mask" "F.Paste")
			(net "M_J_DQ<9>")
		)
		(pad "17" smd rect
			(at 0 13.599922 90)
			(size 1.8034 0.508)
			(layers "F.Cu" "F.Mask" "F.Paste")
			(net "GND")
		)
		(pad "18" smd rect
			(at 0 14.45006 90)
			(size 1.8034 0.508)
			(layers "F.Cu" "F.Mask" "F.Paste")
			(net "M_J_DQS_DP<10>")
		)
		(pad "19" smd rect
			(at 0 15.299944 90)
			(size 1.8034 0.508)
			(layers "F.Cu" "F.Mask" "F.Paste")
			(net "M_J_DQS_DN<10>")
		)
		(pad "20" smd rect
			(at 0 16.150082 90)
			(size 1.8034 0.508)
			(layers "F.Cu" "F.Mask" "F.Paste")
			(net "GND")
		)
		(pad "21" smd rect
			(at 0 16.999966 90)
			(size 1.8034 0.508)
			(layers "F.Cu" "F.Mask" "F.Paste")
			(net "M_J_DQ<15>")
		)
		(pad "22" smd rect
			(at 0 17.850104 90)
			(size 1.8034 0.508)
			(layers "F.Cu" "F.Mask" "F.Paste")
			(net "GND")
		)
		(pad "23" smd rect
			(at 0 18.699988 90)
			(size 1.8034 0.508)
			(layers "F.Cu" "F.Mask" "F.Paste")
			(net "M_J_DQ<11>")
		)
		(pad "24" smd rect
			(at 0 19.550126 90)
			(size 1.8034 0.508)
			(layers "F.Cu" "F.Mask" "F.Paste")
			(net "GND")
		)
		(pad "25" smd rect
			(at 0 20.40001 90)
			(size 1.8034 0.508)
			(layers "F.Cu" "F.Mask" "F.Paste")
			(net "M_J_DQ<21>")
		)
		(pad "26" smd rect
			(at 0 21.249894 90)
			(size 1.8034 0.508)
			(layers "F.Cu" "F.Mask" "F.Paste")
			(net "GND")
		)
		(pad "27" smd rect
			(at 0 22.100032 90)
			(size 1.8034 0.508)
			(layers "F.Cu" "F.Mask" "F.Paste")
			(net "M_J_DQ<17>")
		)
		(pad "28" smd rect
			(at 0 22.949916 90)
			(size 1.8034 0.508)
			(layers "F.Cu" "F.Mask" "F.Paste")
			(net "GND")
		)
		(pad "29" smd rect
			(at 0 23.800054 90)
			(size 1.8034 0.508)
			(layers "F.Cu" "F.Mask" "F.Paste")
			(net "M_J_DQS_DP<11>")
		)
		(pad "30" smd rect
			(at 0 24.649938 90)
			(size 1.8034 0.508)
			(layers "F.Cu" "F.Mask" "F.Paste")
			(net "M_J_DQS_DN<11>")
		)
		(pad "31" smd rect
			(at 0 25.500076 90)
			(size 1.8034 0.508)
			(layers "F.Cu" "F.Mask" "F.Paste")
			(net "GND")
		)
		(pad "32" smd rect
			(at 0 26.34996 90)
			(size 1.8034 0.508)
			(layers "F.Cu" "F.Mask" "F.Paste")
			(net "M_J_DQ<23>")
		)
		(pad "33" smd rect
			(at 0 27.200098 90)
			(size 1.8034 0.508)
			(layers "F.Cu" "F.Mask" "F.Paste")
			(net "GND")
		)
		(pad "34" smd rect
			(at 0 28.049982 90)
			(size 1.8034 0.508)
			(layers "F.Cu" "F.Mask" "F.Paste")
			(net "M_J_DQ<19>")
		)
		(pad "35" smd rect
			(at 0 28.90012 90)
			(size 1.8034 0.508)
			(layers "F.Cu" "F.Mask" "F.Paste")
			(net "GND")
		)
		(pad "36" smd rect
			(at 0 29.750004 90)
			(size 1.8034 0.508)
			(layers "F.Cu" "F.Mask" "F.Paste")
			(net "M_J_DQ<29>")
		)
		(pad "37" smd rect
			(at 0 30.599888 90)
			(size 1.8034 0.508)
			(layers "F.Cu" "F.Mask" "F.Paste")
			(net "GND")
		)
		(pad "38" smd rect
			(at 0 31.450026 90)
			(size 1.8034 0.508)
			(layers "F.Cu" "F.Mask" "F.Paste")
			(net "M_J_DQ<25>")
		)
		(pad "39" smd rect
			(at 0 32.29991 90)
			(size 1.8034 0.508)
			(layers "F.Cu" "F.Mask" "F.Paste")
			(net "GND")
		)
		(pad "40" smd rect
			(at 0 33.150048 90)
			(size 1.8034 0.508)
			(layers "F.Cu" "F.Mask" "F.Paste")
			(net "M_J_DQS_DP<12>")
		)
		(pad "41" smd rect
			(at 0 33.999932 90)
			(size 1.8034 0.508)
			(layers "F.Cu" "F.Mask" "F.Paste")
			(net "M_J_DQS_DN<12>")
		)
		(pad "42" smd rect
			(at 0 34.85007 90)
			(size 1.8034 0.508)
			(layers "F.Cu" "F.Mask" "F.Paste")
			(net "GND")
		)
		(pad "43" smd rect
			(at 0 35.699954 90)
			(size 1.8034 0.508)
			(layers "F.Cu" "F.Mask" "F.Paste")
			(net "M_J_DQ<31>")
		)
		(pad "44" smd rect
			(at 0 36.550092 90)
			(size 1.8034 0.508)
			(layers "F.Cu" "F.Mask" "F.Paste")
			(net "GND")
		)
		(pad "45" smd rect
			(at 0 37.399976 90)
			(size 1.8034 0.508)
			(layers "F.Cu" "F.Mask" "F.Paste")
			(net "M_J_DQ<27>")
		)
		(pad "46" smd rect
			(at 0 38.250114 90)
			(size 1.8034 0.508)
			(layers "F.Cu" "F.Mask" "F.Paste")
			(net "GND")
		)
		(pad "47" smd rect
			(at 0 39.099998 90)
			(size 1.8034 0.508)
			(layers "F.Cu" "F.Mask" "F.Paste")
			(net "M_J_ECC<5>")
		)
		(pad "48" smd rect
			(at 0 39.949882 90)
			(size 1.8034 0.508)
			(layers "F.Cu" "F.Mask" "F.Paste")
			(net "GND")
		)
		(pad "49" smd rect
			(at 0 40.80002 90)
			(size 1.8034 0.508)
			(layers "F.Cu" "F.Mask" "F.Paste")
			(net "M_J_ECC<1>")
		)
		(pad "50" smd rect
			(at 0 41.649904 90)
			(size 1.8034 0.508)
			(layers "F.Cu" "F.Mask" "F.Paste")
			(net "GND")
		)
		(pad "51" smd rect
			(at 0 42.500042 90)
			(size 1.8034 0.508)
			(layers "F.Cu" "F.Mask" "F.Paste")
			(net "M_J_DQS_DP<17>")
		)
		(pad "52" smd rect
			(at 0 43.349926 90)
			(size 1.8034 0.508)
			(layers "F.Cu" "F.Mask" "F.Paste")
			(net "M_J_DQS_DN<17>")
		)
		(pad "53" smd rect
			(at 0 44.200064 90)
			(size 1.8034 0.508)
			(layers "F.Cu" "F.Mask" "F.Paste")
			(net "GND")
		)
		(pad "54" smd rect
			(at 0 45.049948 90)
			(size 1.8034 0.508)
			(layers "F.Cu" "F.Mask" "F.Paste")
			(net "M_J_ECC<7>")
		)
		(pad "55" smd rect
			(at 0 45.900086 90)
			(size 1.8034 0.508)
			(layers "F.Cu" "F.Mask" "F.Paste")
			(net "GND")
		)
		(pad "56" smd rect
			(at 0 46.74997 90)
			(size 1.8034 0.508)
			(layers "F.Cu" "F.Mask" "F.Paste")
			(net "M_J_ECC<3>")
		)
		(pad "57" smd rect
			(at 0 47.600108 90)
			(size 1.8034 0.508)
			(layers "F.Cu" "F.Mask" "F.Paste")
			(net "GND")
		)
		(pad "58" smd rect
			(at 0 48.449992 90)
			(size 1.8034 0.508)
			(layers "F.Cu" "F.Mask" "F.Paste")
			(net "M_GHJ_RST_N")
		)
		(pad "59" smd rect
			(at 0 49.299876 90)
			(size 1.8034 0.508)
			(layers "F.Cu" "F.Mask" "F.Paste")
			(net "PVDDQ_GHJ")
		)
		(pad "60" smd rect
			(at 0 50.150014 90)
			(size 1.8034 0.508)
			(layers "F.Cu" "F.Mask" "F.Paste")
			(net "M_J_CKE<0>")
		)
		(pad "61" smd rect
			(at 0 50.999898 90)
			(size 1.8034 0.508)
			(layers "F.Cu" "F.Mask" "F.Paste")
			(net "PVDDQ_GHJ")
		)
		(pad "62" smd rect
			(at 0 51.850036 90)
			(size 1.8034 0.508)
			(layers "F.Cu" "F.Mask" "F.Paste")
			(net "M_J_ACT_N")
		)
		(pad "63" smd rect
			(at 0 52.69992 90)
			(size 1.8034 0.508)
			(layers "F.Cu" "F.Mask" "F.Paste")
			(net "M_J_BG<0>")
		)
		(pad "64" smd rect
			(at 0 53.550058 90)
			(size 1.8034 0.508)
			(layers "F.Cu" "F.Mask" "F.Paste")
			(net "PVDDQ_GHJ")
		)
		(pad "65" smd rect
			(at 0 54.399942 90)
			(size 1.8034 0.508)
			(layers "F.Cu" "F.Mask" "F.Paste")
			(net "M_J_MA<12>")
		)
		(pad "66" smd rect
			(at 0 55.25008 90)
			(size 1.8034 0.508)
			(layers "F.Cu" "F.Mask" "F.Paste")
			(net "M_J_MA<9>")
		)
		(pad "67" smd rect
			(at 0 56.099964 90)
			(size 1.8034 0.508)
			(layers "F.Cu" "F.Mask" "F.Paste")
			(net "PVDDQ_GHJ")
		)
		(pad "68" smd rect
			(at 0 56.950102 90)
			(size 1.8034 0.508)
			(layers "F.Cu" "F.Mask" "F.Paste")
			(net "M_J_MA<8>")
		)
		(pad "69" smd rect
			(at 0 57.799986 90)
			(size 1.8034 0.508)
			(layers "F.Cu" "F.Mask" "F.Paste")
			(net "M_J_MA<6>")
		)
		(pad "70" smd rect
			(at 0 58.650124 90)
			(size 1.8034 0.508)
			(layers "F.Cu" "F.Mask" "F.Paste")
			(net "PVDDQ_GHJ")
		)
		(pad "71" smd rect
			(at 0 59.500008 90)
			(size 1.8034 0.508)
			(layers "F.Cu" "F.Mask" "F.Paste")
			(net "M_J_MA<3>")
		)
		(pad "72" smd rect
			(at 0 60.349892 90)
			(size 1.8034 0.508)
			(layers "F.Cu" "F.Mask" "F.Paste")
			(net "M_J_MA<1>")
		)
		(pad "73" smd rect
			(at 0 61.20003 90)
			(size 1.8034 0.508)
			(layers "F.Cu" "F.Mask" "F.Paste")
			(net "PVDDQ_GHJ")
		)
		(pad "74" smd rect
			(at 0 62.049914 90)
			(size 1.8034 0.508)
			(layers "F.Cu" "F.Mask" "F.Paste")
			(net "M_J_CLK_DP<0>")
		)
		(pad "75" smd rect
			(at 0 62.900052 90)
			(size 1.8034 0.508)
			(layers "F.Cu" "F.Mask" "F.Paste")
			(net "M_J_CLK_DN<0>")
		)
		(pad "76" smd rect
			(at 0 63.749936 90)
			(size 1.8034 0.508)
			(layers "F.Cu" "F.Mask" "F.Paste")
			(net "PVDDQ_GHJ")
		)
		(pad "77" smd rect
			(at 0 64.600074 90)
			(size 1.8034 0.508)
			(layers "F.Cu" "F.Mask" "F.Paste")
			(net "PVTT_GHJ")
		)
		(pad "78" smd rect
			(at 0 70.550024 90)
			(size 1.8034 0.508)
			(layers "F.Cu" "F.Mask" "F.Paste")
			(net "FM_DIMM_EVENT_COD_N")
		)
		(pad "79" smd rect
			(at 0 71.399908 90)
			(size 1.8034 0.508)
			(layers "F.Cu" "F.Mask" "F.Paste")
			(net "M_J_MA<0>")
		)
		(pad "80" smd rect
			(at 0 72.250046 90)
			(size 1.8034 0.508)
			(layers "F.Cu" "F.Mask" "F.Paste")
			(net "PVDDQ_GHJ")
		)
		(pad "81" smd rect
			(at 0 73.09993 90)
			(size 1.8034 0.508)
			(layers "F.Cu" "F.Mask" "F.Paste")
			(net "M_J_BA<0>")
		)
		(pad "82" smd rect
			(at 0 73.950068 90)
			(size 1.8034 0.508)
			(layers "F.Cu" "F.Mask" "F.Paste")
			(net "M_J_MA<16>")
		)
		(pad "83" smd rect
			(at 0 74.799952 90)
			(size 1.8034 0.508)
			(layers "F.Cu" "F.Mask" "F.Paste")
			(net "PVDDQ_GHJ")
		)
		(pad "84" smd rect
			(at 0 75.65009 90)
			(size 1.8034 0.508)
			(layers "F.Cu" "F.Mask" "F.Paste")
			(net "M_J_CS_N<0>")
		)
		(pad "85" smd rect
			(at 0 76.499974 90)
			(size 1.8034 0.508)
			(layers "F.Cu" "F.Mask" "F.Paste")
			(net "PVDDQ_GHJ")
		)
		(pad "86" smd rect
			(at 0 77.350112 90)
			(size 1.8034 0.508)
			(layers "F.Cu" "F.Mask" "F.Paste")
			(net "M_J_MA<15>")
		)
		(pad "87" smd rect
			(at 0 78.199996 90)
			(size 1.8034 0.508)
			(layers "F.Cu" "F.Mask" "F.Paste")
			(net "M_J_ODT<0>")
		)
		(pad "88" smd rect
			(at 0 79.04988 90)
			(size 1.8034 0.508)
			(layers "F.Cu" "F.Mask" "F.Paste")
			(net "PVDDQ_GHJ")
		)
		(pad "89" smd rect
			(at 0 79.900018 90)
			(size 1.8034 0.508)
			(layers "F.Cu" "F.Mask" "F.Paste")
			(net "M_J_CS_N<1>")
		)
		(pad "90" smd rect
			(at 0 80.749902 90)
			(size 1.8034 0.508)
			(layers "F.Cu" "F.Mask" "F.Paste")
			(net "PVDDQ_GHJ")
		)
		(pad "91" smd rect
			(at 0 81.60004 90)
			(size 1.8034 0.508)
			(layers "F.Cu" "F.Mask" "F.Paste")
			(net "M_J_ODT<1>")
		)
		(pad "92" smd rect
			(at 0 82.449924 90)
			(size 1.8034 0.508)
			(layers "F.Cu" "F.Mask" "F.Paste")
			(net "PVDDQ_GHJ")
		)
		(pad "93" smd rect
			(at 0 83.300062 90)
			(size 1.8034 0.508)
			(layers "F.Cu" "F.Mask" "F.Paste")
			(net "M_J_CS_N<2>")
		)
		(pad "94" smd rect
			(at 0 84.149946 90)
			(size 1.8034 0.508)
			(layers "F.Cu" "F.Mask" "F.Paste")
			(net "GND")
		)
		(pad "95" smd rect
			(at 0 85.000084 90)
			(size 1.8034 0.508)
			(layers "F.Cu" "F.Mask" "F.Paste")
			(net "M_J_DQ<37>")
		)
		(pad "96" smd rect
			(at 0 85.849968 90)
			(size 1.8034 0.508)
			(layers "F.Cu" "F.Mask" "F.Paste")
			(net "GND")
		)
		(pad "97" smd rect
			(at 0 86.700106 90)
			(size 1.8034 0.508)
			(layers "F.Cu" "F.Mask" "F.Paste")
			(net "M_J_DQ<33>")
		)
		(pad "98" smd rect
			(at 0 87.54999 90)
			(size 1.8034 0.508)
			(layers "F.Cu" "F.Mask" "F.Paste")
			(net "GND")
		)
		(pad "99" smd rect
			(at 0 88.399874 90)
			(size 1.8034 0.508)
			(layers "F.Cu" "F.Mask" "F.Paste")
			(net "M_J_DQS_DP<13>")
		)
		(pad "100" smd rect
			(at 0 89.250012 90)
			(size 1.8034 0.508)
			(layers "F.Cu" "F.Mask" "F.Paste")
			(net "M_J_DQS_DN<13>")
		)
		(pad "101" smd rect
			(at 0 90.099896 90)
			(size 1.8034 0.508)
			(layers "F.Cu" "F.Mask" "F.Paste")
			(net "GND")
		)
		(pad "102" smd rect
			(at 0 90.950034 90)
			(size 1.8034 0.508)
			(layers "F.Cu" "F.Mask" "F.Paste")
			(net "M_J_DQ<39>")
		)
		(pad "103" smd rect
			(at 0 91.799918 90)
			(size 1.8034 0.508)
			(layers "F.Cu" "F.Mask" "F.Paste")
			(net "GND")
		)
		(pad "104" smd rect
			(at 0 92.650056 90)
			(size 1.8034 0.508)
			(layers "F.Cu" "F.Mask" "F.Paste")
			(net "M_J_DQ<35>")
		)
		(pad "105" smd rect
			(at 0 93.49994 90)
			(size 1.8034 0.508)
			(layers "F.Cu" "F.Mask" "F.Paste")
			(net "GND")
		)
		(pad "106" smd rect
			(at 0 94.350078 90)
			(size 1.8034 0.508)
			(layers "F.Cu" "F.Mask" "F.Paste")
			(net "M_J_DQ<45>")
		)
		(pad "107" smd rect
			(at 0 95.199962 90)
			(size 1.8034 0.508)
			(layers "F.Cu" "F.Mask" "F.Paste")
			(net "GND")
		)
		(pad "108" smd rect
			(at 0 96.0501 90)
			(size 1.8034 0.508)
			(layers "F.Cu" "F.Mask" "F.Paste")
			(net "M_J_DQ<41>")
		)
		(pad "109" smd rect
			(at 0 96.899984 90)
			(size 1.8034 0.508)
			(layers "F.Cu" "F.Mask" "F.Paste")
			(net "GND")
		)
		(pad "110" smd rect
			(at 0 97.750122 90)
			(size 1.8034 0.508)
			(layers "F.Cu" "F.Mask" "F.Paste")
			(net "M_J_DQS_DP<14>")
		)
		(pad "111" smd rect
			(at 0 98.600006 90)
			(size 1.8034 0.508)
			(layers "F.Cu" "F.Mask" "F.Paste")
			(net "M_J_DQS_DN<14>")
		)
		(pad "112" smd rect
			(at 0 99.44989 90)
			(size 1.8034 0.508)
			(layers "F.Cu" "F.Mask" "F.Paste")
			(net "GND")
		)
		(pad "113" smd rect
			(at 0 100.300028 90)
			(size 1.8034 0.508)
			(layers "F.Cu" "F.Mask" "F.Paste")
			(net "M_J_DQ<47>")
		)
		(pad "114" smd rect
			(at 0 101.149912 90)
			(size 1.8034 0.508)
			(layers "F.Cu" "F.Mask" "F.Paste")
			(net "GND")
		)
		(pad "115" smd rect
			(at 0 102.00005 90)
			(size 1.8034 0.508)
			(layers "F.Cu" "F.Mask" "F.Paste")
			(net "M_J_DQ<43>")
		)
		(pad "116" smd rect
			(at 0 102.849934 90)
			(size 1.8034 0.508)
			(layers "F.Cu" "F.Mask" "F.Paste")
			(net "GND")
		)
		(pad "117" smd rect
			(at 0 103.700072 90)
			(size 1.8034 0.508)
			(layers "F.Cu" "F.Mask" "F.Paste")
			(net "M_J_DQ<53>")
		)
		(pad "118" smd rect
			(at 0 104.549956 90)
			(size 1.8034 0.508)
			(layers "F.Cu" "F.Mask" "F.Paste")
			(net "GND")
		)
		(pad "119" smd rect
			(at 0 105.400094 90)
			(size 1.8034 0.508)
			(layers "F.Cu" "F.Mask" "F.Paste")
			(net "M_J_DQ<49>")
		)
		(pad "120" smd rect
			(at 0 106.249978 90)
			(size 1.8034 0.508)
			(layers "F.Cu" "F.Mask" "F.Paste")
			(net "GND")
		)
	)
)
